# T6G (Grand Teton) — schematic netlist excerpt (pin names and nets, part order shuffled) for the footprints in the layout excerpt that follows; sources: Cadence DE-HDL packaged netlist, KiCad conversion of 04192023_DAF0TMB3IC0_F0TG_MB_C_brd_V02_OCP.brd

C627  Q_CAP  0.1UF 10V 10% X7S  pkg C0201  page 290 : A = P0V9_CPU0_RT1_2A ; B = GND

U49  PI3CSW12ZUAEX  IC  pkg UQFN10_0-5_2X1-5  page 186
  \1d+\  = SMB_RT_CPU0_P0_ROM_MUX_1D_SCL
  \1d-\  = SMB_RT_CPU0_P0_ROM_MUX_1D_SDA
  \2d+\  = SMB_RT_CPU0_P0_ROM_MUX_2D_SCL
  \2d-\  = SMB_RT_CPU0_P0_ROM_MUX_2D_SDA
  GND  = GND
  \oe#\  = RT_ROM_MUX5_OE_N
  \d-\  = SMB_RT_CPU0_P0_ROM_R_SDA
  \d+\  = SMB_RT_CPU0_P0_ROM_R_SCL
  S  = FM_SMB_RT_ROM_MUX5_SEL
  VDD  = P3V3_AUX

R589  Q_RES  0 5% CHIP  pkg 0402LF  page 29 : A = SCM_USB_OC_BU_R_N ; B = SCM_USB_OC_BUF_N

(kicad_pcb
	(version 20260206)
	(generator "pcbnew")
	(generator_version "10.0")
	(general
		(thickness 1.6)
		(legacy_teardrops no)
	)
	(paper "A4")
	(title_block
		(title "04192023_DAF0TMB3IC0_F0TG_MB_C_brd_V02_OCP.brd")
		(comment 1 "Grand Teton / footprints 7585-7587 of 8354")
	)
	(layers
		(0 "F.Cu" signal "TOP")
		(4 "In1.Cu" signal "GND")
		(6 "In2.Cu" signal "IN1")
		(8 "In3.Cu" signal "GND1")
		(10 "In4.Cu" signal "IN2")
		(12 "In5.Cu" signal "GND2")
		(14 "In6.Cu" signal "IN3")
		(16 "In7.Cu" signal "GND3")
		(18 "In8.Cu" signal "VCC")
		(20 "In9.Cu" signal "VCC1")
		(22 "In10.Cu" signal "GND4")
		(24 "In11.Cu" signal "IN4")
		(26 "In12.Cu" signal "GND5")
		(28 "In13.Cu" signal "IN5")
		(30 "In14.Cu" signal "GND6")
		(32 "In15.Cu" signal "IN6")
		(34 "In16.Cu" signal "GND7")
		(2 "B.Cu" signal "BOTTOM")
		(9 "F.Adhes" user "F.Adhesive")
		(11 "B.Adhes" user "B.Adhesive")
		(13 "F.Paste" user "Package Geometry/Pastemask Top")
		(15 "B.Paste" user "Package Geometry/Pastemask Bottom")
		(5 "F.SilkS" user "Ref Des/Silkscreen Top")
		(7 "B.SilkS" user "Ref Des/Silkscreen Bottom")
		(1 "F.Mask" user "Board Geometry/Soldermask Top")
		(3 "B.Mask" user "Board Geometry/Soldermask Bottom")
		(17 "Dwgs.User" user "User.Drawings")
		(19 "Cmts.User" user "User.Comments")
		(21 "Eco1.User" user "User.Eco1")
		(23 "Eco2.User" user "User.Eco2")
		(25 "Edge.Cuts" user "Board Geometry/Outline")
		(27 "Margin" user)
		(31 "F.CrtYd" user "Package Geometry/Place Bound Top")
		(29 "B.CrtYd" user "Package Geometry/Place Bound Bottom")
		(35 "F.Fab" user "Ref Des/Assembly Top")
		(33 "B.Fab" user "Ref Des/Assembly Bottom")
	)
	(footprint ""
		(layer "B.Cu")
		(at 397.788892 -201.308208)
		(property "Reference" "R589"
			(at 0 0 0)
			(layer "B.SilkS")
			(hide yes)
			(effects
				(font
					(size 1.27 1.27)
				)
				(justify mirror)
			)
		)
		(property "Value" ""
			(at 0 0 0)
			(layer "B.Fab")
			(effects
				(font
					(size 1.27 1.27)
				)
				(justify mirror)
			)
		)
		(duplicate_pad_numbers_are_jumpers no)
		(fp_line
			(start -0.7874 -0.4064)
			(end -0.7874 0.4064)
			(stroke
				(width 0.1524)
				(type default)
			)
			(layer "B.SilkS")
		)
		(fp_line
			(start -0.7874 0.4064)
			(end 0.7874 0.4064)
			(stroke
				(width 0.1524)
				(type default)
			)
			(layer "B.SilkS")
		)
		(fp_line
			(start 0.7874 -0.4064)
			(end -0.7874 -0.4064)
			(stroke
				(width 0.1524)
				(type default)
			)
			(layer "B.SilkS")
		)
		(fp_line
			(start 0.7874 0.4064)
			(end 0.7874 -0.4064)
			(stroke
				(width 0.1524)
				(type default)
			)
			(layer "B.SilkS")
		)
		(fp_line
			(start -0.67945 -0.3048)
			(end -0.67945 0.3048)
			(stroke
				(width 0.1)
				(type default)
			)
			(layer "B.Fab")
		)
		(fp_line
			(start -0.67945 0.3048)
			(end -0.120396 0.3048)
			(stroke
				(width 0.1)
				(type default)
			)
			(layer "B.Fab")
		)
		(fp_line
			(start -0.12065 -0.3048)
			(end -0.67945 -0.3048)
			(stroke
				(width 0.1)
				(type default)
			)
			(layer "B.Fab")
		)
		(fp_line
			(start -0.12065 -0.2794)
			(end -0.12065 -0.3048)
			(stroke
				(width 0.1)
				(type default)
			)
			(layer "B.Fab")
		)
		(fp_line
			(start -0.120396 0.2794)
			(end 0.12065 0.2794)
			(stroke
				(width 0.1)
				(type default)
			)
			(layer "B.Fab")
		)
		(fp_line
			(start -0.120396 0.3048)
			(end -0.120396 0.2794)
			(stroke
				(width 0.1)
				(type default)
			)
			(layer "B.Fab")
		)
		(fp_line
			(start 0.12065 -0.305054)
			(end 0.12065 -0.2794)
			(stroke
				(width 0.1)
				(type default)
			)
			(layer "B.Fab")
		)
		(fp_line
			(start 0.12065 -0.2794)
			(end -0.12065 -0.2794)
			(stroke
				(width 0.1)
				(type default)
			)
			(layer "B.Fab")
		)
		(fp_line
			(start 0.12065 0.2794)
			(end 0.12065 0.3048)
			(stroke
				(width 0.1)
				(type default)
			)
			(layer "B.Fab")
		)
		(fp_line
			(start 0.12065 0.3048)
			(end 0.67945 0.3048)
			(stroke
				(width 0.1)
				(type default)
			)
			(layer "B.Fab")
		)
		(fp_line
			(start 0.67945 -0.305054)
			(end 0.12065 -0.305054)
			(stroke
				(width 0.1)
				(type default)
			)
			(layer "B.Fab")
		)
		(fp_line
			(start 0.67945 0.3048)
			(end 0.67945 -0.305054)
			(stroke
				(width 0.1)
				(type default)
			)
			(layer "B.Fab")
		)
		(pad "1" smd circle
			(at 0.40005 0 180)
			(size 0 0)
			(layers "B.Cu" "B.Mask" "B.Paste")
			(net "SCM_USB_OC_BU_R_N")
		)
		(pad "2" smd circle
			(at -0.40005 0 180)
			(size 0 0)
			(layers "B.Cu" "B.Mask" "B.Paste")
			(net "SCM_USB_OC_BUF_N")
		)
	)
	(footprint ""
		(layer "B.Cu")
		(at 350.446086 -396.393162 -90)
		(property "Reference" "C627"
			(at 0 0 90)
			(layer "B.SilkS")
			(hide yes)
			(effects
				(font
					(size 1.27 1.27)
				)
				(justify mirror)
			)
		)
		(property "Value" ""
			(at 0 0 90)
			(layer "B.Fab")
			(effects
				(font
					(size 1.27 1.27)
				)
				(justify mirror)
			)
		)
		(duplicate_pad_numbers_are_jumpers no)
		(fp_line
			(start -0.299974 0.150114)
			(end 0.299974 0.150114)
			(stroke
				(width 0.1)
				(type default)
			)
			(layer "B.Fab")
		)
		(fp_line
			(start 0.299974 0.150114)
			(end 0.299974 -0.150114)
			(stroke
				(width 0.1)
				(type default)
			)
			(layer "B.Fab")
		)
		(fp_line
			(start -0.299974 -0.150114)
			(end -0.299974 0.150114)
			(stroke
				(width 0.1)
				(type default)
			)
			(layer "B.Fab")
		)
		(fp_line
			(start 0.299974 -0.150114)
			(end -0.299974 -0.150114)
			(stroke
				(width 0.1)
				(type default)
			)
			(layer "B.Fab")
		)
		(pad "1" smd rect
			(at 0.2667 0 90)
			(size 0.3048 0.381)
			(layers "B.Cu" "B.Mask" "B.Paste")
			(net "P0V9_CPU0_RT1_2A")
		)
		(pad "2" smd rect
			(at -0.2667 0 90)
			(size 0.3048 0.381)
			(layers "B.Cu" "B.Mask" "B.Paste")
			(net "GND")
		)
	)
	(footprint ""
		(layer "B.Cu")
		(at 298.565316 -425.288964)
		(property "Reference" "U49"
			(at 0.087884 -4.071366 0)
			(unlocked yes)
			(layer "B.SilkS")
			(effects
				(font
					(size 0.7874 0.5842)
					(thickness 0.1524)
				)
				(justify mirror)
			)
		)
		(property "Value" ""
			(at 0 0 0)
			(layer "B.Fab")
			(effects
				(font
					(size 1.27 1.27)
				)
				(justify mirror)
			)
		)
		(duplicate_pad_numbers_are_jumpers no)
		(fp_line
			(start -1.03378 -1.284478)
			(end -1.03378 1.284478)
			(stroke
				(width 0.1524)
				(type default)
			)
			(layer "B.SilkS")
		)
		(fp_line
			(start -1.03378 1.284478)
			(end 1.03378 1.284478)
			(stroke
				(width 0.1524)
				(type default)
			)
			(layer "B.SilkS")
		)
		(fp_line
			(start 1.03378 -1.284478)
			(end -1.03378 -1.284478)
			(stroke
				(width 0.1524)
				(type default)
			)
			(layer "B.SilkS")
		)
		(fp_line
			(start 1.03378 1.284478)
			(end 1.03378 -1.284478)
			(stroke
				(width 0.1524)
				(type default)
			)
			(layer "B.SilkS")
		)
		(fp_poly
			(pts
				(xy 1.201674 -0.750062) (xy 1.806702 -0.447548) (xy 1.806702 -1.052576)
			)
			(stroke
				(width 0)
				(type default)
			)
			(fill yes)
			(layer "B.SilkS")
		)
		(fp_line
			(start -0.774954 -1.02489)
			(end -0.774954 1.02489)
			(stroke
				(width 0.1)
				(type default)
			)
			(layer "B.Fab")
		)
		(fp_line
			(start -0.774954 1.02489)
			(end 0.774954 1.02489)
			(stroke
				(width 0.1)
				(type default)
			)
			(layer "B.Fab")
		)
		(fp_line
			(start 0.774954 -1.02489)
			(end -0.774954 -1.02489)
			(stroke
				(width 0.1)
				(type default)
			)
			(layer "B.Fab")
		)
		(fp_line
			(start 0.774954 1.02489)
			(end 0.774954 -1.02489)
			(stroke
				(width 0.1)
				(type default)
			)
			(layer "B.Fab")
		)
		(fp_poly
			(pts
				(xy 1.201674 -0.750062) (xy 1.806702 -0.447548) (xy 1.806702 -1.052576)
			)
			(stroke
				(width 0)
				(type default)
			)
			(fill yes)
			(layer "B.Fab")
		)
		(pad "1" smd rect
			(at 0.64008 -0.750062 90)
			(size 0.3048 0.5334)
			(layers "B.Cu" "B.Mask" "B.Paste")
			(net "SMB_RT_CPU0_P0_ROM_MUX_1D_SCL")
		)
		(pad "2" smd rect
			(at 0.64008 -0.249936 90)
			(size 0.254 0.5334)
			(layers "B.Cu" "B.Mask" "B.Paste")
			(net "SMB_RT_CPU0_P0_ROM_MUX_1D_SDA")
		)
		(pad "3" smd rect
			(at 0.64008 0.249936 90)
			(size 0.254 0.5334)
			(layers "B.Cu" "B.Mask" "B.Paste")
			(net "SMB_RT_CPU0_P0_ROM_MUX_2D_SCL")
		)
		(pad "4" smd rect
			(at 0.64008 0.750062 90)
			(size 0.3048 0.5334)
			(layers "B.Cu" "B.Mask" "B.Paste")
			(net "SMB_RT_CPU0_P0_ROM_MUX_2D_SDA")
		)
		(pad "5" smd rect
			(at 0 0.839978 180)
			(size 0.3302 0.635)
			(layers "B.Cu" "B.Mask" "B.Paste")
			(net "GND")
		)
		(pad "6" smd rect
			(at -0.64008 0.750062 90)
			(size 0.3048 0.5334)
			(layers "B.Cu" "B.Mask" "B.Paste")
			(net "RT_ROM_MUX5_OE_N")
		)
		(pad "7" smd rect
			(at -0.64008 0.249936 90)
			(size 0.254 0.5334)
			(layers "B.Cu" "B.Mask" "B.Paste")
			(net "SMB_RT_CPU0_P0_ROM_R_SDA")
		)
		(pad "8" smd rect
			(at -0.64008 -0.249936 90)
			(size 0.254 0.5334)
			(layers "B.Cu" "B.Mask" "B.Paste")
			(net "SMB_RT_CPU0_P0_ROM_R_SCL")
		)
		(pad "9" smd rect
			(at -0.64008 -0.750062 90)
			(size 0.3048 0.5334)
			(layers "B.Cu" "B.Mask" "B.Paste")
			(net "FM_SMB_RT_ROM_MUX5_SEL")
		)
		(pad "10" smd rect
			(at 0 -0.839978 180)
			(size 0.3302 0.635)
			(layers "B.Cu" "B.Mask" "B.Paste")
			(net "P3V3_AUX")
		)
	)
)
